(kicad_pcb
	(version 20260206)
	(generator "pcbnew")
	(generator_version "10.0")
	(general
		(thickness 1.6)
		(legacy_teardrops no)
	)
	(paper "A4")
	(title_block
		(title "12092022_DA0F0TMDCD0_F0T_Management_Board_D_brd_V3_OCP.brd")
		(comment 1 "Grand Teton / footprints 1172-1177 of 1440")
	)
	(layers
		(0 "F.Cu" signal "TOP")
		(4 "In1.Cu" signal "GND")
		(6 "In2.Cu" signal "IN1")
		(8 "In3.Cu" signal "GND1")
		(10 "In4.Cu" signal "IN2")
		(12 "In5.Cu" signal "VCC")
		(14 "In6.Cu" signal "VCC1")
		(16 "In7.Cu" signal "IN3")
		(18 "In8.Cu" signal "GND2")
		(20 "In9.Cu" signal "IN4")
		(22 "In10.Cu" signal "GND3")
		(2 "B.Cu" signal "BOTTOM")
		(9 "F.Adhes" user "F.Adhesive")
		(11 "B.Adhes" user "B.Adhesive")
		(13 "F.Paste" user "Package Geometry/Pastemask Top")
		(15 "B.Paste" user "Package Geometry/Pastemask Bottom")
		(5 "F.SilkS" user "Ref Des/Silkscreen Top")
		(7 "B.SilkS" user "Ref Des/Silkscreen Bottom")
		(1 "F.Mask" user "Board Geometry/Soldermask Top")
		(3 "B.Mask" user "Board Geometry/Soldermask Bottom")
		(17 "Dwgs.User" user "User.Drawings")
		(19 "Cmts.User" user "User.Comments")
		(21 "Eco1.User" user "User.Eco1")
		(23 "Eco2.User" user "User.Eco2")
		(25 "Edge.Cuts" user "Board Geometry/Outline")
		(27 "Margin" user)
		(31 "F.CrtYd" user "Package Geometry/Place Bound Top")
		(29 "B.CrtYd" user "Package Geometry/Place Bound Bottom")
		(35 "F.Fab" user "Ref Des/Assembly Top")
		(33 "B.Fab" user "Ref Des/Assembly Bottom")
	)
	(footprint ""
		(layer "B.Cu")
		(at 63.9572 -91.2114)
		(property "Reference" "R739"
			(at 0 0 0)
			(layer "B.SilkS")
			(hide yes)
			(effects
				(font
					(size 1.27 1.27)
				)
				(justify mirror)
			)
		)
		(property "Value" ""
			(at 0 0 0)
			(layer "B.Fab")
			(effects
				(font
					(size 1.27 1.27)
				)
				(justify mirror)
			)
		)
		(duplicate_pad_numbers_are_jumpers no)
		(fp_line
			(start -0.7874 -0.4064)
			(end -0.7874 0.4064)
			(stroke
				(width 0.1524)
				(type default)
			)
			(layer "B.SilkS")
		)
		(fp_line
			(start -0.7874 0.4064)
			(end 0.7874 0.4064)
			(stroke
				(width 0.1524)
				(type default)
			)
			(layer "B.SilkS")
		)
		(fp_line
			(start 0.7874 -0.4064)
			(end -0.7874 -0.4064)
			(stroke
				(width 0.1524)
				(type default)
			)
			(layer "B.SilkS")
		)
		(fp_line
			(start 0.7874 0.4064)
			(end 0.7874 -0.4064)
			(stroke
				(width 0.1524)
				(type default)
			)
			(layer "B.SilkS")
		)
		(fp_line
			(start -0.67945 -0.3048)
			(end -0.67945 0.3048)
			(stroke
				(width 0.1)
				(type default)
			)
			(layer "B.Fab")
		)
		(fp_line
			(start -0.67945 0.3048)
			(end -0.120396 0.3048)
			(stroke
				(width 0.1)
				(type default)
			)
			(layer "B.Fab")
		)
		(fp_line
			(start -0.12065 -0.3048)
			(end -0.67945 -0.3048)
			(stroke
				(width 0.1)
				(type default)
			)
			(layer "B.Fab")
		)
		(fp_line
			(start -0.12065 -0.2794)
			(end -0.12065 -0.3048)
			(stroke
				(width 0.1)
				(type default)
			)
			(layer "B.Fab")
		)
		(fp_line
			(start -0.120396 0.2794)
			(end 0.12065 0.2794)
			(stroke
				(width 0.1)
				(type default)
			)
			(layer "B.Fab")
		)
		(fp_line
			(start -0.120396 0.3048)
			(end -0.120396 0.2794)
			(stroke
				(width 0.1)
				(type default)
			)
			(layer "B.Fab")
		)
		(fp_line
			(start 0.12065 -0.305054)
			(end 0.12065 -0.2794)
			(stroke
				(width 0.1)
				(type default)
			)
			(layer "B.Fab")
		)
		(fp_line
			(start 0.12065 -0.2794)
			(end -0.12065 -0.2794)
			(stroke
				(width 0.1)
				(type default)
			)
			(layer "B.Fab")
		)
		(fp_line
			(start 0.12065 0.2794)
			(end 0.12065 0.3048)
			(stroke
				(width 0.1)
				(type default)
			)
			(layer "B.Fab")
		)
		(fp_line
			(start 0.12065 0.3048)
			(end 0.67945 0.3048)
			(stroke
				(width 0.1)
				(type default)
			)
			(layer "B.Fab")
		)
		(fp_line
			(start 0.67945 -0.305054)
			(end 0.12065 -0.305054)
			(stroke
				(width 0.1)
				(type default)
			)
			(layer "B.Fab")
		)
		(fp_line
			(start 0.67945 0.3048)
			(end 0.67945 -0.305054)
			(stroke
				(width 0.1)
				(type default)
			)
			(layer "B.Fab")
		)
		(pad "1" smd circle
			(at 0.40005 0 180)
			(size 0 0)
			(layers "B.Cu" "B.Mask" "B.Paste")
			(net "P3V3_AUX")
		)
		(pad "2" smd circle
			(at -0.40005 0 180)
			(size 0 0)
			(layers "B.Cu" "B.Mask" "B.Paste")
			(net "LED_POSTCODE_A1")
		)
	)
	(footprint ""
		(layer "B.Cu")
		(at 12.319 -101.854 90)
		(property "Reference" "D23"
			(at -0.0762 1.37033 270)
			(unlocked yes)
			(layer "B.SilkS")
			(effects
				(font
					(size 0.7874 0.5842)
					(thickness 0.1524)
				)
				(justify left mirror)
			)
		)
		(property "Value" ""
			(at 0 0 90)
			(layer "B.Fab")
			(effects
				(font
					(size 1.27 1.27)
				)
				(justify mirror)
			)
		)
		(duplicate_pad_numbers_are_jumpers no)
		(fp_line
			(start 2.050796 -0.700024)
			(end -2.050796 -0.700024)
			(stroke
				(width 0.1524)
				(type default)
			)
			(layer "B.SilkS")
		)
		(fp_line
			(start -2.050796 -0.700024)
			(end -2.050796 0.700024)
			(stroke
				(width 0.1524)
				(type default)
			)
			(layer "B.SilkS")
		)
		(fp_line
			(start -2.064004 -0.6985)
			(end -2.229104 -0.6985)
			(stroke
				(width 0.1524)
				(type default)
			)
			(layer "B.SilkS")
		)
		(fp_line
			(start -2.152904 -0.6985)
			(end -2.343404 -0.6985)
			(stroke
				(width 0.1524)
				(type default)
			)
			(layer "B.SilkS")
		)
		(fp_line
			(start -2.229104 -0.6985)
			(end -2.229104 0.6985)
			(stroke
				(width 0.1524)
				(type default)
			)
			(layer "B.SilkS")
		)
		(fp_line
			(start -2.343404 -0.6985)
			(end -2.343404 0.6985)
			(stroke
				(width 0.1524)
				(type default)
			)
			(layer "B.SilkS")
		)
		(fp_line
			(start -2.064004 -0.6731)
			(end -2.064004 -0.6985)
			(stroke
				(width 0.1524)
				(type default)
			)
			(layer "B.SilkS")
		)
		(fp_line
			(start 0.30607 -0.500126)
			(end 0.30607 0.500126)
			(stroke
				(width 0.1524)
				(type default)
			)
			(layer "B.SilkS")
		)
		(fp_line
			(start -0.293878 -0.500126)
			(end -0.293878 0.500126)
			(stroke
				(width 0.1524)
				(type default)
			)
			(layer "B.SilkS")
		)
		(fp_line
			(start -0.193802 0)
			(end 0.30607 -0.500126)
			(stroke
				(width 0.1524)
				(type default)
			)
			(layer "B.SilkS")
		)
		(fp_line
			(start 0.30607 0.500126)
			(end -0.193802 0)
			(stroke
				(width 0.1524)
				(type default)
			)
			(layer "B.SilkS")
		)
		(fp_line
			(start -2.051304 0.635)
			(end -2.152904 0.635)
			(stroke
				(width 0.1524)
				(type default)
			)
			(layer "B.SilkS")
		)
		(fp_line
			(start -2.152904 0.635)
			(end -2.152904 -0.6985)
			(stroke
				(width 0.1524)
				(type default)
			)
			(layer "B.SilkS")
		)
		(fp_line
			(start -2.051304 0.6985)
			(end -2.051304 0.635)
			(stroke
				(width 0.1524)
				(type default)
			)
			(layer "B.SilkS")
		)
		(fp_line
			(start -2.229104 0.6985)
			(end -2.051304 0.6985)
			(stroke
				(width 0.1524)
				(type default)
			)
			(layer "B.SilkS")
		)
		(fp_line
			(start -2.343404 0.6985)
			(end -2.216404 0.6985)
			(stroke
				(width 0.1524)
				(type default)
			)
			(layer "B.SilkS")
		)
		(fp_line
			(start 2.050796 0.700024)
			(end 2.050796 -0.700024)
			(stroke
				(width 0.1524)
				(type default)
			)
			(layer "B.SilkS")
		)
		(fp_line
			(start -2.050796 0.700024)
			(end 2.050796 0.700024)
			(stroke
				(width 0.1524)
				(type default)
			)
			(layer "B.SilkS")
		)
		(fp_line
			(start 0.899922 -0.700024)
			(end -0.899922 -0.700024)
			(stroke
				(width 0.1)
				(type default)
			)
			(layer "B.Fab")
		)
		(fp_line
			(start -0.899922 -0.700024)
			(end -0.899922 0.700024)
			(stroke
				(width 0.1)
				(type default)
			)
			(layer "B.Fab")
		)
		(fp_line
			(start 0.899922 0.700024)
			(end 0.899922 -0.700024)
			(stroke
				(width 0.1)
				(type default)
			)
			(layer "B.Fab")
		)
		(fp_line
			(start -0.899922 0.700024)
			(end 0.899922 0.700024)
			(stroke
				(width 0.1)
				(type default)
			)
			(layer "B.Fab")
		)
		(fp_text user "+"
			(at 3.01625 1.016 0)
			(unlocked yes)
			(layer "B.SilkS")
			(effects
				(font
					(size 1.905 1.4224)
					(thickness 0.1524)
				)
				(justify left mirror)
			)
		)
		(fp_text user "-"
			(at -2.2352 1.36525 270)
			(unlocked yes)
			(layer "B.SilkS")
			(effects
				(font
					(size 1.905 1.4224)
					(thickness 0.1524)
				)
				(justify left mirror)
			)
		)
		(fp_text user "-"
			(at -3.880104 0.23495 270)
			(unlocked yes)
			(layer "B.Fab")
			(effects
				(font
					(size 1.905 1.4224)
					(thickness 0.1524)
				)
				(justify left mirror)
			)
		)
		(fp_text user "+"
			(at 3.123946 0.762 0)
			(unlocked yes)
			(layer "B.Fab")
			(effects
				(font
					(size 1.905 1.4224)
					(thickness 0.1524)
				)
				(justify left mirror)
			)
		)
		(pad "1" smd rect
			(at 1.199896 0)
			(size 0.6604 1.3716)
			(layers "B.Cu" "B.Mask" "B.Paste")
			(net "PWRGD_P5V_AUX")
		)
		(pad "2" smd rect
			(at -1.199896 0 180)
			(size 0.6604 1.3716)
			(layers "B.Cu" "B.Mask" "B.Paste")
			(net "PWRGD_P5V_AUX_R1")
		)
	)
	(footprint ""
		(layer "B.Cu")
		(at 19.472656 -96.012 -90)
		(property "Reference" "C250"
			(at 0 0 90)
			(layer "B.SilkS")
			(hide yes)
			(effects
				(font
					(size 1.27 1.27)
				)
				(justify mirror)
			)
		)
		(property "Value" ""
			(at 0 0 90)
			(layer "B.Fab")
			(effects
				(font
					(size 1.27 1.27)
				)
				(justify mirror)
			)
		)
		(duplicate_pad_numbers_are_jumpers no)
		(fp_line
			(start -0.69215 0.2921)
			(end 0.69215 0.2921)
			(stroke
				(width 0.1524)
				(type default)
			)
			(layer "B.SilkS")
		)
		(fp_line
			(start 0.69215 0.2921)
			(end 0.69215 -0.2921)
			(stroke
				(width 0.1524)
				(type default)
			)
			(layer "B.SilkS")
		)
		(fp_line
			(start -0.69215 -0.2921)
			(end -0.69215 0.2921)
			(stroke
				(width 0.1524)
				(type default)
			)
			(layer "B.SilkS")
		)
		(fp_line
			(start 0.69215 -0.2921)
			(end -0.69215 -0.2921)
			(stroke
				(width 0.1524)
				(type default)
			)
			(layer "B.SilkS")
		)
		(fp_line
			(start -0.51435 0.2794)
			(end 0.51435 0.2794)
			(stroke
				(width 0.1)
				(type default)
			)
			(layer "B.Fab")
		)
		(fp_line
			(start 0.51435 0.2794)
			(end 0.51435 -0.2794)
			(stroke
				(width 0.1)
				(type default)
			)
			(layer "B.Fab")
		)
		(fp_line
			(start -0.51435 -0.2794)
			(end -0.51435 0.2794)
			(stroke
				(width 0.1)
				(type default)
			)
			(layer "B.Fab")
		)
		(fp_line
			(start 0.51435 -0.2794)
			(end -0.51435 -0.2794)
			(stroke
				(width 0.1)
				(type default)
			)
			(layer "B.Fab")
		)
		(pad "1" smd circle
			(at 0.40005 0 90)
			(size 0 0)
			(layers "B.Cu" "B.Mask" "B.Paste")
			(net "PVCCA_AUX_PLD")
		)
		(pad "2" smd circle
			(at -0.40005 0 90)
			(size 0 0)
			(layers "B.Cu" "B.Mask" "B.Paste")
			(net "GND")
		)
		(zone
			(layer "B.Cu")
			(hatch none 0.5)
			(connect_pads
				(clearance 0)
			)
			(min_thickness 0.25)
			(keepout
				(tracks not_allowed)
				(vias allowed)
				(pads allowed)
				(copperpour not_allowed)
				(footprints allowed)
			)
			(placement
				(enabled no)
				(sheetname "")
			)
			(fill
				(thermal_gap 0.5)
				(thermal_bridge_width 0.5)
				(island_removal_mode 0)
			)
			(polygon
				(pts
					(xy 19.385026 -95.8215) (xy 19.32686 -95.91294) (xy 19.32686 -96.11233) (xy 19.385026 -96.2025)
					(xy 19.560286 -96.2025) (xy 19.618706 -96.11233) (xy 19.618706 -95.91294) (xy 19.56054 -95.8215)
				)
			)
		)
	)
	(footprint ""
		(layer "B.Cu")
		(at 61.876686 -30.87751 -90)
		(property "Reference" "R157"
			(at 0 0 90)
			(layer "B.SilkS")
			(hide yes)
			(effects
				(font
					(size 1.27 1.27)
				)
				(justify mirror)
			)
		)
		(property "Value" ""
			(at 0 0 90)
			(layer "B.Fab")
			(effects
				(font
					(size 1.27 1.27)
				)
				(justify mirror)
			)
		)
		(duplicate_pad_numbers_are_jumpers no)
		(fp_line
			(start -0.7874 0.4064)
			(end 0.7874 0.4064)
			(stroke
				(width 0.1524)
				(type default)
			)
			(layer "B.SilkS")
		)
		(fp_line
			(start 0.7874 0.4064)
			(end 0.7874 -0.4064)
			(stroke
				(width 0.1524)
				(type default)
			)
			(layer "B.SilkS")
		)
		(fp_line
			(start -0.7874 -0.4064)
			(end -0.7874 0.4064)
			(stroke
				(width 0.1524)
				(type default)
			)
			(layer "B.SilkS")
		)
		(fp_line
			(start 0.7874 -0.4064)
			(end -0.7874 -0.4064)
			(stroke
				(width 0.1524)
				(type default)
			)
			(layer "B.SilkS")
		)
		(fp_line
			(start -0.67945 0.3048)
			(end -0.120396 0.3048)
			(stroke
				(width 0.1)
				(type default)
			)
			(layer "B.Fab")
		)
		(fp_line
			(start -0.120396 0.3048)
			(end -0.120396 0.2794)
			(stroke
				(width 0.1)
				(type default)
			)
			(layer "B.Fab")
		)
		(fp_line
			(start 0.12065 0.3048)
			(end 0.67945 0.3048)
			(stroke
				(width 0.1)
				(type default)
			)
			(layer "B.Fab")
		)
		(fp_line
			(start 0.67945 0.3048)
			(end 0.67945 -0.305054)
			(stroke
				(width 0.1)
				(type default)
			)
			(layer "B.Fab")
		)
		(fp_line
			(start -0.120396 0.2794)
			(end 0.12065 0.2794)
			(stroke
				(width 0.1)
				(type default)
			)
			(layer "B.Fab")
		)
		(fp_line
			(start 0.12065 0.2794)
			(end 0.12065 0.3048)
			(stroke
				(width 0.1)
				(type default)
			)
			(layer "B.Fab")
		)
		(fp_line
			(start -0.12065 -0.2794)
			(end -0.12065 -0.3048)
			(stroke
				(width 0.1)
				(type default)
			)
			(layer "B.Fab")
		)
		(fp_line
			(start 0.12065 -0.2794)
			(end -0.12065 -0.2794)
			(stroke
				(width 0.1)
				(type default)
			)
			(layer "B.Fab")
		)
		(fp_line
			(start -0.67945 -0.3048)
			(end -0.67945 0.3048)
			(stroke
				(width 0.1)
				(type default)
			)
			(layer "B.Fab")
		)
		(fp_line
			(start -0.12065 -0.3048)
			(end -0.67945 -0.3048)
			(stroke
				(width 0.1)
				(type default)
			)
			(layer "B.Fab")
		)
		(fp_line
			(start 0.12065 -0.305054)
			(end 0.12065 -0.2794)
			(stroke
				(width 0.1)
				(type default)
			)
			(layer "B.Fab")
		)
		(fp_line
			(start 0.67945 -0.305054)
			(end 0.12065 -0.305054)
			(stroke
				(width 0.1)
				(type default)
			)
			(layer "B.Fab")
		)
		(pad "1" smd circle
			(at 0.40005 0 90)
			(size 0 0)
			(layers "B.Cu" "B.Mask" "B.Paste")
			(net "UART_BMC_1_TXD_R")
		)
		(pad "2" smd circle
			(at -0.40005 0 90)
			(size 0 0)
			(layers "B.Cu" "B.Mask" "B.Paste")
			(net "UART_BMC_1_TXD")
		)
	)
	(footprint ""
		(layer "B.Cu")
		(at 49.205896 -47.67072 -90)
		(property "Reference" "C72"
			(at 0 0 90)
			(layer "B.SilkS")
			(hide yes)
			(effects
				(font
					(size 1.27 1.27)
				)
				(justify mirror)
			)
		)
		(property "Value" ""
			(at 0 0 90)
			(layer "B.Fab")
			(effects
				(font
					(size 1.27 1.27)
				)
				(justify mirror)
			)
		)
		(duplicate_pad_numbers_are_jumpers no)
		(fp_line
			(start -0.7874 0.4064)
			(end 0.7874 0.4064)
			(stroke
				(width 0.1524)
				(type default)
			)
			(layer "B.SilkS")
		)
		(fp_line
			(start 0.7874 0.4064)
			(end 0.7874 -0.4064)
			(stroke
				(width 0.1524)
				(type default)
			)
			(layer "B.SilkS")
		)
		(fp_line
			(start -0.7874 -0.4064)
			(end -0.7874 0.4064)
			(stroke
				(width 0.1524)
				(type default)
			)
			(layer "B.SilkS")
		)
		(fp_line
			(start 0.7874 -0.4064)
			(end -0.7874 -0.4064)
			(stroke
				(width 0.1524)
				(type default)
			)
			(layer "B.SilkS")
		)
		(fp_line
			(start -0.67945 0.3048)
			(end -0.120396 0.3048)
			(stroke
				(width 0.1)
				(type default)
			)
			(layer "B.Fab")
		)
		(fp_line
			(start -0.120396 0.3048)
			(end -0.120396 0.2794)
			(stroke
				(width 0.1)
				(type default)
			)
			(layer "B.Fab")
		)
		(fp_line
			(start 0.12065 0.3048)
			(end 0.67945 0.3048)
			(stroke
				(width 0.1)
				(type default)
			)
			(layer "B.Fab")
		)
		(fp_line
			(start 0.67945 0.3048)
			(end 0.67945 -0.305054)
			(stroke
				(width 0.1)
				(type default)
			)
			(layer "B.Fab")
		)
		(fp_line
			(start -0.120396 0.2794)
			(end 0.12065 0.2794)
			(stroke
				(width 0.1)
				(type default)
			)
			(layer "B.Fab")
		)
		(fp_line
			(start 0.12065 0.2794)
			(end 0.12065 0.3048)
			(stroke
				(width 0.1)
				(type default)
			)
			(layer "B.Fab")
		)
		(fp_line
			(start -0.12065 -0.2794)
			(end -0.12065 -0.3048)
			(stroke
				(width 0.1)
				(type default)
			)
			(layer "B.Fab")
		)
		(fp_line
			(start 0.12065 -0.2794)
			(end -0.12065 -0.2794)
			(stroke
				(width 0.1)
				(type default)
			)
			(layer "B.Fab")
		)
		(fp_line
			(start -0.67945 -0.3048)
			(end -0.67945 0.3048)
			(stroke
				(width 0.1)
				(type default)
			)
			(layer "B.Fab")
		)
		(fp_line
			(start -0.12065 -0.3048)
			(end -0.67945 -0.3048)
			(stroke
				(width 0.1)
				(type default)
			)
			(layer "B.Fab")
		)
		(fp_line
			(start 0.12065 -0.305054)
			(end 0.12065 -0.2794)
			(stroke
				(width 0.1)
				(type default)
			)
			(layer "B.Fab")
		)
		(fp_line
			(start 0.67945 -0.305054)
			(end 0.12065 -0.305054)
			(stroke
				(width 0.1)
				(type default)
			)
			(layer "B.Fab")
		)
		(pad "1" smd circle
			(at 0.40005 0 90)
			(size 0 0)
			(layers "B.Cu" "B.Mask" "B.Paste")
			(net "P1V2_AUX")
		)
		(pad "2" smd circle
			(at -0.40005 0 90)
			(size 0 0)
			(layers "B.Cu" "B.Mask" "B.Paste")
			(net "GND")
		)
	)
	(footprint ""
		(layer "B.Cu")
		(at 36.957 -32.766)
		(property "Reference" "L2"
			(at 0 0 0)
			(layer "B.SilkS")
			(hide yes)
			(effects
				(font
					(size 1.27 1.27)
				)
				(justify mirror)
			)
		)
		(property "Value" ""
			(at 0 0 0)
			(layer "B.Fab")
			(effects
				(font
					(size 1.27 1.27)
				)
				(justify mirror)
			)
		)
		(duplicate_pad_numbers_are_jumpers no)
		(fp_line
			(start -1.27 0.5842)
			(end -1.27 -0.5842)
			(stroke
				(width 0.1524)
				(type default)
			)
			(layer "B.SilkS")
		)
		(fp_line
			(start -1.27 0.5842)
			(end 1.27 0.5842)
			(stroke
				(width 0.1524)
				(type default)
			)
			(layer "B.SilkS")
		)
		(fp_line
			(start -0.127 0.5842)
			(end -0.127 -0.5842)
			(stroke
				(width 0.1524)
				(type default)
			)
			(layer "B.SilkS")
		)
		(fp_line
			(start 0.127 0.5842)
			(end 0.127 -0.5842)
			(stroke
				(width 0.1524)
				(type default)
			)
			(layer "B.SilkS")
		)
		(fp_line
			(start 1.27 -0.5842)
			(end -1.27 -0.5842)
			(stroke
				(width 0.1524)
				(type default)
			)
			(layer "B.SilkS")
		)
		(fp_line
			(start 1.27 -0.5588)
			(end 1.27 -0.5842)
			(stroke
				(width 0.1524)
				(type default)
			)
			(layer "B.SilkS")
		)
		(fp_line
			(start 1.27 0.5842)
			(end 1.27 -0.5842)
			(stroke
				(width 0.1524)
				(type default)
			)
			(layer "B.SilkS")
		)
		(fp_line
			(start -1.1938 -0.406654)
			(end -1.1938 0.4064)
			(stroke
				(width 0.1)
				(type default)
			)
			(layer "B.Fab")
		)
		(fp_line
			(start -1.1938 0.4064)
			(end -0.9144 0.4064)
			(stroke
				(width 0.1)
				(type default)
			)
			(layer "B.Fab")
		)
		(fp_line
			(start -0.9144 -0.508)
			(end -0.9144 -0.406654)
			(stroke
				(width 0.1)
				(type default)
			)
			(layer "B.Fab")
		)
		(fp_line
			(start -0.9144 -0.406654)
			(end -1.1938 -0.406654)
			(stroke
				(width 0.1)
				(type default)
			)
			(layer "B.Fab")
		)
		(fp_line
			(start -0.9144 0.4064)
			(end -0.9144 0.508)
			(stroke
				(width 0.1)
				(type default)
			)
			(layer "B.Fab")
		)
		(fp_line
			(start -0.9144 0.508)
			(end 0.9144 0.508)
			(stroke
				(width 0.1)
				(type default)
			)
			(layer "B.Fab")
		)
		(fp_line
			(start 0.9144 -0.508)
			(end -0.9144 -0.508)
			(stroke
				(width 0.1)
				(type default)
			)
			(layer "B.Fab")
		)
		(fp_line
			(start 0.9144 -0.406654)
			(end 0.9144 -0.508)
			(stroke
				(width 0.1)
				(type default)
			)
			(layer "B.Fab")
		)
		(fp_line
			(start 0.9144 0.406654)
			(end 1.194308 0.406654)
			(stroke
				(width 0.1)
				(type default)
			)
			(layer "B.Fab")
		)
		(fp_line
			(start 0.9144 0.508)
			(end 0.9144 0.406654)
			(stroke
				(width 0.1)
				(type default)
			)
			(layer "B.Fab")
		)
		(fp_line
			(start 1.194308 -0.406654)
			(end 0.9144 -0.406654)
			(stroke
				(width 0.1)
				(type default)
			)
			(layer "B.Fab")
		)
		(fp_line
			(start 1.194308 0.406654)
			(end 1.194308 -0.406654)
			(stroke
				(width 0.1)
				(type default)
			)
			(layer "B.Fab")
		)
		(pad "1" smd rect
			(at 0.7366 0 270)
			(size 0.7112 0.8128)
			(layers "B.Cu" "B.Mask" "B.Paste")
			(net "P1V2_AUX")
		)
		(pad "2" smd rect
			(at -0.7366 0 270)
			(size 0.7112 0.8128)
			(layers "B.Cu" "B.Mask" "B.Paste")
			(net "P3V3_STBY_PLLAHVDD")
		)
	)
)
